(kicad_pcb
	(version 20260206)
	(generator "pcbnew")
	(generator_version "10.0")
	(general
		(thickness 1.6)
		(legacy_teardrops no)
	)
	(paper "A4")
	(title_block
		(title "04192023_DAF0TMB3IC0_F0TG_MB_C_brd_V02_OCP.brd")
		(comment 1 "Grand Teton / footprints 6683-6690 of 8354")
	)
	(layers
		(0 "F.Cu" signal "TOP")
		(4 "In1.Cu" signal "GND")
		(6 "In2.Cu" signal "IN1")
		(8 "In3.Cu" signal "GND1")
		(10 "In4.Cu" signal "IN2")
		(12 "In5.Cu" signal "GND2")
		(14 "In6.Cu" signal "IN3")
		(16 "In7.Cu" signal "GND3")
		(18 "In8.Cu" signal "VCC")
		(20 "In9.Cu" signal "VCC1")
		(22 "In10.Cu" signal "GND4")
		(24 "In11.Cu" signal "IN4")
		(26 "In12.Cu" signal "GND5")
		(28 "In13.Cu" signal "IN5")
		(30 "In14.Cu" signal "GND6")
		(32 "In15.Cu" signal "IN6")
		(34 "In16.Cu" signal "GND7")
		(2 "B.Cu" signal "BOTTOM")
		(9 "F.Adhes" user "F.Adhesive")
		(11 "B.Adhes" user "B.Adhesive")
		(13 "F.Paste" user "Package Geometry/Pastemask Top")
		(15 "B.Paste" user "Package Geometry/Pastemask Bottom")
		(5 "F.SilkS" user "Ref Des/Silkscreen Top")
		(7 "B.SilkS" user "Ref Des/Silkscreen Bottom")
		(1 "F.Mask" user "Board Geometry/Soldermask Top")
		(3 "B.Mask" user "Board Geometry/Soldermask Bottom")
		(17 "Dwgs.User" user "User.Drawings")
		(19 "Cmts.User" user "User.Comments")
		(21 "Eco1.User" user "User.Eco1")
		(23 "Eco2.User" user "User.Eco2")
		(25 "Edge.Cuts" user "Board Geometry/Outline")
		(27 "Margin" user)
		(31 "F.CrtYd" user "Package Geometry/Place Bound Top")
		(29 "B.CrtYd" user "Package Geometry/Place Bound Bottom")
		(35 "F.Fab" user "Ref Des/Assembly Top")
		(33 "B.Fab" user "Ref Des/Assembly Bottom")
	)
	(footprint ""
		(layer "B.Cu")
		(at 388.382256 -182.867554 -90)
		(property "Reference" "PC557_4"
			(at 0 0 90)
			(layer "B.SilkS")
			(hide yes)
			(effects
				(font
					(size 1.27 1.27)
				)
				(justify mirror)
			)
		)
		(property "Value" ""
			(at 0 0 90)
			(layer "B.Fab")
			(effects
				(font
					(size 1.27 1.27)
				)
				(justify mirror)
			)
		)
		(duplicate_pad_numbers_are_jumpers no)
		(fp_line
			(start -1.524 0.762)
			(end 1.524 0.762)
			(stroke
				(width 0.1524)
				(type default)
			)
			(layer "B.SilkS")
		)
		(fp_line
			(start 1.524 0.762)
			(end 1.524 -0.762)
			(stroke
				(width 0.1524)
				(type default)
			)
			(layer "B.SilkS")
		)
		(fp_line
			(start -1.524 -0.762)
			(end -1.524 0.762)
			(stroke
				(width 0.1524)
				(type default)
			)
			(layer "B.SilkS")
		)
		(fp_line
			(start 1.524 -0.762)
			(end -1.524 -0.762)
			(stroke
				(width 0.1524)
				(type default)
			)
			(layer "B.SilkS")
		)
		(fp_line
			(start -1.1049 0.724916)
			(end -1.1049 -0.724916)
			(stroke
				(width 0.1)
				(type default)
			)
			(layer "B.Fab")
		)
		(fp_line
			(start 1.1049 0.724916)
			(end -1.1049 0.724916)
			(stroke
				(width 0.1)
				(type default)
			)
			(layer "B.Fab")
		)
		(fp_line
			(start -1.1049 -0.724916)
			(end 1.1049 -0.724916)
			(stroke
				(width 0.1)
				(type default)
			)
			(layer "B.Fab")
		)
		(fp_line
			(start 1.1049 -0.724916)
			(end 1.1049 0.724916)
			(stroke
				(width 0.1)
				(type default)
			)
			(layer "B.Fab")
		)
		(pad "1" smd rect
			(at 0.889 0 270)
			(size 1.016 1.27)
			(layers "B.Cu" "B.Mask" "B.Paste")
			(net "SW_P12V_AUX_PVDDCR_CPU0_P0_FLT")
		)
		(pad "2" smd rect
			(at -0.889 0 270)
			(size 1.016 1.27)
			(layers "B.Cu" "B.Mask" "B.Paste")
			(net "GND")
		)
	)
	(footprint ""
		(layer "B.Cu")
		(at 155.406344 -386.766562 90)
		(property "Reference" "C377"
			(at 0 0 90)
			(layer "B.SilkS")
			(hide yes)
			(effects
				(font
					(size 1.27 1.27)
				)
				(justify mirror)
			)
		)
		(property "Value" ""
			(at 0 0 90)
			(layer "B.Fab")
			(effects
				(font
					(size 1.27 1.27)
				)
				(justify mirror)
			)
		)
		(duplicate_pad_numbers_are_jumpers no)
		(fp_line
			(start 0.299974 -0.150114)
			(end -0.299974 -0.150114)
			(stroke
				(width 0.1)
				(type default)
			)
			(layer "B.Fab")
		)
		(fp_line
			(start -0.299974 -0.150114)
			(end -0.299974 0.150114)
			(stroke
				(width 0.1)
				(type default)
			)
			(layer "B.Fab")
		)
		(fp_line
			(start 0.299974 0.150114)
			(end 0.299974 -0.150114)
			(stroke
				(width 0.1)
				(type default)
			)
			(layer "B.Fab")
		)
		(fp_line
			(start -0.299974 0.150114)
			(end 0.299974 0.150114)
			(stroke
				(width 0.1)
				(type default)
			)
			(layer "B.Fab")
		)
		(pad "1" smd rect
			(at 0.2667 0 270)
			(size 0.3048 0.381)
			(layers "B.Cu" "B.Mask" "B.Paste")
			(net "P1V8_CPU1_RT2_1A")
		)
		(pad "2" smd rect
			(at -0.2667 0 270)
			(size 0.3048 0.381)
			(layers "B.Cu" "B.Mask" "B.Paste")
			(net "GND")
		)
	)
	(footprint ""
		(layer "B.Cu")
		(at 116.372386 -268.418564)
		(property "Reference" "C2400"
			(at 0 0 0)
			(layer "B.SilkS")
			(hide yes)
			(effects
				(font
					(size 1.27 1.27)
				)
				(justify mirror)
			)
		)
		(property "Value" ""
			(at 0 0 0)
			(layer "B.Fab")
			(effects
				(font
					(size 1.27 1.27)
				)
				(justify mirror)
			)
		)
		(duplicate_pad_numbers_are_jumpers no)
		(fp_line
			(start -0.7874 -0.4064)
			(end -0.7874 0.4064)
			(stroke
				(width 0.1524)
				(type default)
			)
			(layer "B.SilkS")
		)
		(fp_line
			(start -0.7874 0.4064)
			(end 0.7874 0.4064)
			(stroke
				(width 0.1524)
				(type default)
			)
			(layer "B.SilkS")
		)
		(fp_line
			(start 0.7874 -0.4064)
			(end -0.7874 -0.4064)
			(stroke
				(width 0.1524)
				(type default)
			)
			(layer "B.SilkS")
		)
		(fp_line
			(start 0.7874 0.4064)
			(end 0.7874 -0.4064)
			(stroke
				(width 0.1524)
				(type default)
			)
			(layer "B.SilkS")
		)
		(fp_line
			(start -0.67945 -0.3048)
			(end -0.67945 0.3048)
			(stroke
				(width 0.1)
				(type default)
			)
			(layer "B.Fab")
		)
		(fp_line
			(start -0.67945 0.3048)
			(end -0.120396 0.3048)
			(stroke
				(width 0.1)
				(type default)
			)
			(layer "B.Fab")
		)
		(fp_line
			(start -0.12065 -0.3048)
			(end -0.67945 -0.3048)
			(stroke
				(width 0.1)
				(type default)
			)
			(layer "B.Fab")
		)
		(fp_line
			(start -0.12065 -0.2794)
			(end -0.12065 -0.3048)
			(stroke
				(width 0.1)
				(type default)
			)
			(layer "B.Fab")
		)
		(fp_line
			(start -0.120396 0.2794)
			(end 0.12065 0.2794)
			(stroke
				(width 0.1)
				(type default)
			)
			(layer "B.Fab")
		)
		(fp_line
			(start -0.120396 0.3048)
			(end -0.120396 0.2794)
			(stroke
				(width 0.1)
				(type default)
			)
			(layer "B.Fab")
		)
		(fp_line
			(start 0.12065 -0.305054)
			(end 0.12065 -0.2794)
			(stroke
				(width 0.1)
				(type default)
			)
			(layer "B.Fab")
		)
		(fp_line
			(start 0.12065 -0.2794)
			(end -0.12065 -0.2794)
			(stroke
				(width 0.1)
				(type default)
			)
			(layer "B.Fab")
		)
		(fp_line
			(start 0.12065 0.2794)
			(end 0.12065 0.3048)
			(stroke
				(width 0.1)
				(type default)
			)
			(layer "B.Fab")
		)
		(fp_line
			(start 0.12065 0.3048)
			(end 0.67945 0.3048)
			(stroke
				(width 0.1)
				(type default)
			)
			(layer "B.Fab")
		)
		(fp_line
			(start 0.67945 -0.305054)
			(end 0.12065 -0.305054)
			(stroke
				(width 0.1)
				(type default)
			)
			(layer "B.Fab")
		)
		(fp_line
			(start 0.67945 0.3048)
			(end 0.67945 -0.305054)
			(stroke
				(width 0.1)
				(type default)
			)
			(layer "B.Fab")
		)
		(pad "1" smd circle
			(at 0.40005 0 180)
			(size 0 0)
			(layers "B.Cu" "B.Mask" "B.Paste")
			(net "PVDDCR_CPU1_P1")
		)
		(pad "2" smd circle
			(at -0.40005 0 180)
			(size 0 0)
			(layers "B.Cu" "B.Mask" "B.Paste")
			(net "GND")
		)
	)
	(footprint ""
		(layer "B.Cu")
		(at 91.392502 -205.14945 90)
		(property "Reference" "R538"
			(at 0 0 90)
			(layer "B.SilkS")
			(hide yes)
			(effects
				(font
					(size 1.27 1.27)
				)
				(justify mirror)
			)
		)
		(property "Value" ""
			(at 0 0 90)
			(layer "B.Fab")
			(effects
				(font
					(size 1.27 1.27)
				)
				(justify mirror)
			)
		)
		(duplicate_pad_numbers_are_jumpers no)
		(fp_line
			(start 0.7874 -0.4064)
			(end -0.7874 -0.4064)
			(stroke
				(width 0.1524)
				(type default)
			)
			(layer "B.SilkS")
		)
		(fp_line
			(start -0.7874 -0.4064)
			(end -0.7874 0.4064)
			(stroke
				(width 0.1524)
				(type default)
			)
			(layer "B.SilkS")
		)
		(fp_line
			(start 0.7874 0.4064)
			(end 0.7874 -0.4064)
			(stroke
				(width 0.1524)
				(type default)
			)
			(layer "B.SilkS")
		)
		(fp_line
			(start -0.7874 0.4064)
			(end 0.7874 0.4064)
			(stroke
				(width 0.1524)
				(type default)
			)
			(layer "B.SilkS")
		)
		(fp_line
			(start 0.67945 -0.305054)
			(end 0.12065 -0.305054)
			(stroke
				(width 0.1)
				(type default)
			)
			(layer "B.Fab")
		)
		(fp_line
			(start 0.12065 -0.305054)
			(end 0.12065 -0.2794)
			(stroke
				(width 0.1)
				(type default)
			)
			(layer "B.Fab")
		)
		(fp_line
			(start -0.12065 -0.3048)
			(end -0.67945 -0.3048)
			(stroke
				(width 0.1)
				(type default)
			)
			(layer "B.Fab")
		)
		(fp_line
			(start -0.67945 -0.3048)
			(end -0.67945 0.3048)
			(stroke
				(width 0.1)
				(type default)
			)
			(layer "B.Fab")
		)
		(fp_line
			(start 0.12065 -0.2794)
			(end -0.12065 -0.2794)
			(stroke
				(width 0.1)
				(type default)
			)
			(layer "B.Fab")
		)
		(fp_line
			(start -0.12065 -0.2794)
			(end -0.12065 -0.3048)
			(stroke
				(width 0.1)
				(type default)
			)
			(layer "B.Fab")
		)
		(fp_line
			(start 0.12065 0.2794)
			(end 0.12065 0.3048)
			(stroke
				(width 0.1)
				(type default)
			)
			(layer "B.Fab")
		)
		(fp_line
			(start -0.120396 0.2794)
			(end 0.12065 0.2794)
			(stroke
				(width 0.1)
				(type default)
			)
			(layer "B.Fab")
		)
		(fp_line
			(start 0.67945 0.3048)
			(end 0.67945 -0.305054)
			(stroke
				(width 0.1)
				(type default)
			)
			(layer "B.Fab")
		)
		(fp_line
			(start 0.12065 0.3048)
			(end 0.67945 0.3048)
			(stroke
				(width 0.1)
				(type default)
			)
			(layer "B.Fab")
		)
		(fp_line
			(start -0.120396 0.3048)
			(end -0.120396 0.2794)
			(stroke
				(width 0.1)
				(type default)
			)
			(layer "B.Fab")
		)
		(fp_line
			(start -0.67945 0.3048)
			(end -0.120396 0.3048)
			(stroke
				(width 0.1)
				(type default)
			)
			(layer "B.Fab")
		)
		(pad "1" smd circle
			(at 0.40005 0 270)
			(size 0 0)
			(layers "B.Cu" "B.Mask" "B.Paste")
			(net "CPU1_XTRIG_L5")
		)
		(pad "2" smd circle
			(at -0.40005 0 270)
			(size 0 0)
			(layers "B.Cu" "B.Mask" "B.Paste")
			(net "PVDD18_S5_P1")
		)
	)
	(footprint ""
		(layer "B.Cu")
		(at 81.118964 -390.560052 90)
		(property "Reference" "C329"
			(at 0 0 90)
			(layer "B.SilkS")
			(hide yes)
			(effects
				(font
					(size 1.27 1.27)
				)
				(justify mirror)
			)
		)
		(property "Value" ""
			(at 0 0 90)
			(layer "B.Fab")
			(effects
				(font
					(size 1.27 1.27)
				)
				(justify mirror)
			)
		)
		(duplicate_pad_numbers_are_jumpers no)
		(fp_line
			(start 0.7874 -0.4064)
			(end -0.7874 -0.4064)
			(stroke
				(width 0.1524)
				(type default)
			)
			(layer "B.SilkS")
		)
		(fp_line
			(start -0.7874 -0.4064)
			(end -0.7874 0.4064)
			(stroke
				(width 0.1524)
				(type default)
			)
			(layer "B.SilkS")
		)
		(fp_line
			(start 0.7874 0.4064)
			(end 0.7874 -0.4064)
			(stroke
				(width 0.1524)
				(type default)
			)
			(layer "B.SilkS")
		)
		(fp_line
			(start -0.7874 0.4064)
			(end 0.7874 0.4064)
			(stroke
				(width 0.1524)
				(type default)
			)
			(layer "B.SilkS")
		)
		(fp_line
			(start 0.67945 -0.305054)
			(end 0.12065 -0.305054)
			(stroke
				(width 0.1)
				(type default)
			)
			(layer "B.Fab")
		)
		(fp_line
			(start 0.12065 -0.305054)
			(end 0.12065 -0.2794)
			(stroke
				(width 0.1)
				(type default)
			)
			(layer "B.Fab")
		)
		(fp_line
			(start -0.12065 -0.3048)
			(end -0.67945 -0.3048)
			(stroke
				(width 0.1)
				(type default)
			)
			(layer "B.Fab")
		)
		(fp_line
			(start -0.67945 -0.3048)
			(end -0.67945 0.3048)
			(stroke
				(width 0.1)
				(type default)
			)
			(layer "B.Fab")
		)
		(fp_line
			(start 0.12065 -0.2794)
			(end -0.12065 -0.2794)
			(stroke
				(width 0.1)
				(type default)
			)
			(layer "B.Fab")
		)
		(fp_line
			(start -0.12065 -0.2794)
			(end -0.12065 -0.3048)
			(stroke
				(width 0.1)
				(type default)
			)
			(layer "B.Fab")
		)
		(fp_line
			(start 0.12065 0.2794)
			(end 0.12065 0.3048)
			(stroke
				(width 0.1)
				(type default)
			)
			(layer "B.Fab")
		)
		(fp_line
			(start -0.120396 0.2794)
			(end 0.12065 0.2794)
			(stroke
				(width 0.1)
				(type default)
			)
			(layer "B.Fab")
		)
		(fp_line
			(start 0.67945 0.3048)
			(end 0.67945 -0.305054)
			(stroke
				(width 0.1)
				(type default)
			)
			(layer "B.Fab")
		)
		(fp_line
			(start 0.12065 0.3048)
			(end 0.67945 0.3048)
			(stroke
				(width 0.1)
				(type default)
			)
			(layer "B.Fab")
		)
		(fp_line
			(start -0.120396 0.3048)
			(end -0.120396 0.2794)
			(stroke
				(width 0.1)
				(type default)
			)
			(layer "B.Fab")
		)
		(fp_line
			(start -0.67945 0.3048)
			(end -0.120396 0.3048)
			(stroke
				(width 0.1)
				(type default)
			)
			(layer "B.Fab")
		)
		(pad "1" smd circle
			(at 0.40005 0 270)
			(size 0 0)
			(layers "B.Cu" "B.Mask" "B.Paste")
			(net "P0V9_CPU1_RT1_2A")
		)
		(pad "2" smd circle
			(at -0.40005 0 270)
			(size 0 0)
			(layers "B.Cu" "B.Mask" "B.Paste")
			(net "GND")
		)
	)
	(footprint ""
		(layer "B.Cu")
		(at 218.059 -341.884 180)
		(property "Reference" "R6749"
			(at 0 0 0)
			(layer "B.SilkS")
			(hide yes)
			(effects
				(font
					(size 1.27 1.27)
				)
				(justify mirror)
			)
		)
		(property "Value" ""
			(at 0 0 0)
			(layer "B.Fab")
			(effects
				(font
					(size 1.27 1.27)
				)
				(justify mirror)
			)
		)
		(duplicate_pad_numbers_are_jumpers no)
		(fp_line
			(start 0.32512 0.175006)
			(end 0.32512 -0.175006)
			(stroke
				(width 0.1)
				(type default)
			)
			(layer "B.Fab")
		)
		(fp_line
			(start 0.32512 -0.175006)
			(end -0.32512 -0.175006)
			(stroke
				(width 0.1)
				(type default)
			)
			(layer "B.Fab")
		)
		(fp_line
			(start -0.32512 0.175006)
			(end 0.32512 0.175006)
			(stroke
				(width 0.1)
				(type default)
			)
			(layer "B.Fab")
		)
		(fp_line
			(start -0.32512 -0.175006)
			(end -0.32512 0.175006)
			(stroke
				(width 0.1)
				(type default)
			)
			(layer "B.Fab")
		)
		(pad "1" smd rect
			(at 0.2667 0)
			(size 0.3048 0.381)
			(layers "B.Cu" "B.Mask" "B.Paste")
			(net "SMB_RT_CPU1_P2_R_SCL")
		)
		(pad "2" smd rect
			(at -0.2667 0 180)
			(size 0.3048 0.381)
			(layers "B.Cu" "B.Mask" "B.Paste")
			(net "SMB_RT_CPU1_P2_SCL")
		)
	)
	(footprint ""
		(layer "B.Cu")
		(at 344.955876 -66.708782 90)
		(property "Reference" "R3099"
			(at 0 0 90)
			(layer "B.SilkS")
			(hide yes)
			(effects
				(font
					(size 1.27 1.27)
				)
				(justify mirror)
			)
		)
		(property "Value" ""
			(at 0 0 90)
			(layer "B.Fab")
			(effects
				(font
					(size 1.27 1.27)
				)
				(justify mirror)
			)
		)
		(duplicate_pad_numbers_are_jumpers no)
		(fp_line
			(start 0.7874 -0.4064)
			(end -0.7874 -0.4064)
			(stroke
				(width 0.1524)
				(type default)
			)
			(layer "B.SilkS")
		)
		(fp_line
			(start -0.7874 -0.4064)
			(end -0.7874 0.4064)
			(stroke
				(width 0.1524)
				(type default)
			)
			(layer "B.SilkS")
		)
		(fp_line
			(start 0.7874 0.4064)
			(end 0.7874 -0.4064)
			(stroke
				(width 0.1524)
				(type default)
			)
			(layer "B.SilkS")
		)
		(fp_line
			(start -0.7874 0.4064)
			(end 0.7874 0.4064)
			(stroke
				(width 0.1524)
				(type default)
			)
			(layer "B.SilkS")
		)
		(fp_line
			(start 0.67945 -0.305054)
			(end 0.12065 -0.305054)
			(stroke
				(width 0.1)
				(type default)
			)
			(layer "B.Fab")
		)
		(fp_line
			(start 0.12065 -0.305054)
			(end 0.12065 -0.2794)
			(stroke
				(width 0.1)
				(type default)
			)
			(layer "B.Fab")
		)
		(fp_line
			(start -0.12065 -0.3048)
			(end -0.67945 -0.3048)
			(stroke
				(width 0.1)
				(type default)
			)
			(layer "B.Fab")
		)
		(fp_line
			(start -0.67945 -0.3048)
			(end -0.67945 0.3048)
			(stroke
				(width 0.1)
				(type default)
			)
			(layer "B.Fab")
		)
		(fp_line
			(start 0.12065 -0.2794)
			(end -0.12065 -0.2794)
			(stroke
				(width 0.1)
				(type default)
			)
			(layer "B.Fab")
		)
		(fp_line
			(start -0.12065 -0.2794)
			(end -0.12065 -0.3048)
			(stroke
				(width 0.1)
				(type default)
			)
			(layer "B.Fab")
		)
		(fp_line
			(start 0.12065 0.2794)
			(end 0.12065 0.3048)
			(stroke
				(width 0.1)
				(type default)
			)
			(layer "B.Fab")
		)
		(fp_line
			(start -0.120396 0.2794)
			(end 0.12065 0.2794)
			(stroke
				(width 0.1)
				(type default)
			)
			(layer "B.Fab")
		)
		(fp_line
			(start 0.67945 0.3048)
			(end 0.67945 -0.305054)
			(stroke
				(width 0.1)
				(type default)
			)
			(layer "B.Fab")
		)
		(fp_line
			(start 0.12065 0.3048)
			(end 0.67945 0.3048)
			(stroke
				(width 0.1)
				(type default)
			)
			(layer "B.Fab")
		)
		(fp_line
			(start -0.120396 0.3048)
			(end -0.120396 0.2794)
			(stroke
				(width 0.1)
				(type default)
			)
			(layer "B.Fab")
		)
		(fp_line
			(start -0.67945 0.3048)
			(end -0.120396 0.3048)
			(stroke
				(width 0.1)
				(type default)
			)
			(layer "B.Fab")
		)
		(pad "1" smd circle
			(at 0.40005 0 270)
			(size 0 0)
			(layers "B.Cu" "B.Mask" "B.Paste")
			(net "LED_PWRGD_PVDD11_S3_P1_R")
		)
		(pad "2" smd circle
			(at -0.40005 0 270)
			(size 0 0)
			(layers "B.Cu" "B.Mask" "B.Paste")
			(net "P3V3_AUX")
		)
	)
	(footprint ""
		(layer "B.Cu")
		(at 58.490104 -408.517344 90)
		(property "Reference" "C6668"
			(at 0 0 90)
			(layer "B.SilkS")
			(hide yes)
			(effects
				(font
					(size 1.27 1.27)
				)
				(justify mirror)
			)
		)
		(property "Value" ""
			(at 0 0 90)
			(layer "B.Fab")
			(effects
				(font
					(size 1.27 1.27)
				)
				(justify mirror)
			)
		)
		(duplicate_pad_numbers_are_jumpers no)
		(fp_line
			(start 0.299974 -0.150114)
			(end -0.299974 -0.150114)
			(stroke
				(width 0.1)
				(type default)
			)
			(layer "B.Fab")
		)
		(fp_line
			(start -0.299974 -0.150114)
			(end -0.299974 0.150114)
			(stroke
				(width 0.1)
				(type default)
			)
			(layer "B.Fab")
		)
		(fp_line
			(start 0.299974 0.150114)
			(end 0.299974 -0.150114)
			(stroke
				(width 0.1)
				(type default)
			)
			(layer "B.Fab")
		)
		(fp_line
			(start -0.299974 0.150114)
			(end 0.299974 0.150114)
			(stroke
				(width 0.1)
				(type default)
			)
			(layer "B.Fab")
		)
		(pad "1" smd rect
			(at 0.2667 0 270)
			(size 0.3048 0.381)
			(layers "B.Cu" "B.Mask" "B.Paste")
			(net "P5E_CPU1_P1_TX_BUF_C_DN<3>")
		)
		(pad "2" smd rect
			(at -0.2667 0 270)
			(size 0.3048 0.381)
			(layers "B.Cu" "B.Mask" "B.Paste")
			(net "P5E_CPU1_P1_TX_BUF_DN<3>")
		)
	)
)
